(kicad_pcb
	(version 20260206)
	(generator "pcbnew")
	(generator_version "10.0")
	(general
		(thickness 1.6)
		(legacy_teardrops no)
	)
	(paper "A4")
	(title_block
		(title "netronome-mezz — pcbd0082-001_rev01_jul9_a.brd")
		(comment 1 "Open CloudServer (Microsoft) / footprints 61-65 of 714")
	)
	(layers
		(0 "F.Cu" signal "TOP")
		(4 "In1.Cu" signal "02_GND")
		(6 "In2.Cu" signal "03_SIG")
		(8 "In3.Cu" signal "04_SIG")
		(10 "In4.Cu" signal "05_GND")
		(12 "In5.Cu" signal "06_PWR1")
		(14 "In6.Cu" signal "07_SIG")
		(16 "In7.Cu" signal "08_SIG")
		(18 "In8.Cu" signal "09_GND")
		(2 "B.Cu" signal "BOTTOM")
		(9 "F.Adhes" user "F.Adhesive")
		(11 "B.Adhes" user "B.Adhesive")
		(13 "F.Paste" user "Package Geometry/Pastemask Top")
		(15 "B.Paste" user "Package Geometry/Pastemask Bottom")
		(5 "F.SilkS" user "Ref Des/Silkscreen Top")
		(7 "B.SilkS" user "Ref Des/Silkscreen Bottom")
		(1 "F.Mask" user "Board Geometry/Soldermask Top")
		(3 "B.Mask" user "Board Geometry/Soldermask Bottom")
		(17 "Dwgs.User" user "User.Drawings")
		(19 "Cmts.User" user "User.Comments")
		(21 "Eco1.User" user "User.Eco1")
		(23 "Eco2.User" user "User.Eco2")
		(25 "Edge.Cuts" user "Board Geometry/Outline")
		(27 "Margin" user)
		(31 "F.CrtYd" user "Package Geometry/Place Bound Top")
		(29 "B.CrtYd" user "Package Geometry/Place Bound Bottom")
		(35 "F.Fab" user "Ref Des/Assembly Top")
		(33 "B.Fab" user "Ref Des/Assembly Bottom")
		(45 "User.4" user "COMPVAL_TYPE_BOTTOM")
	)
	(footprint ""
		(layer "F.Cu")
		(at 66.802 56.134)
		(property "Reference" "TP67"
			(at 1.397 0.66167 0)
			(unlocked yes)
			(layer "F.SilkS")
			(effects
				(font
					(size 0.7874 0.5842)
					(thickness 0.127)
				)
				(justify left)
			)
		)
		(property "Value" "*"
			(at -0.4826 -0.14732 0)
			(unlocked yes)
			(layer "F.Fab")
			(hide yes)
			(effects
				(font
					(size 1.27 0.9652)
					(thickness 0.000001)
				)
				(justify left)
			)
		)
		(property "Device Type" "TP_SMALL"
			(at -0.4826 -0.14732 0)
			(unlocked yes)
			(layer "F.Fab")
			(hide yes)
			(effects
				(font
					(size 1.27 0.9652)
					(thickness 0.000001)
				)
				(justify left)
			)
		)
		(duplicate_pad_numbers_are_jumpers no)
		(fp_line
			(start -0.8636 -0.8636)
			(end -0.8636 0.8636)
			(stroke
				(width 0.1524)
				(type default)
			)
			(layer "F.SilkS")
		)
		(fp_line
			(start -0.8636 0.8636)
			(end 0.8636 0.8636)
			(stroke
				(width 0.1524)
				(type default)
			)
			(layer "F.SilkS")
		)
		(fp_line
			(start 0.8636 -0.8636)
			(end -0.8636 -0.8636)
			(stroke
				(width 0.1524)
				(type default)
			)
			(layer "F.SilkS")
		)
		(fp_line
			(start 0.8636 0.8636)
			(end 0.8636 -0.8636)
			(stroke
				(width 0.1524)
				(type default)
			)
			(layer "F.SilkS")
		)
		(fp_poly
			(pts
				(xy -0.635 -0.635) (xy -0.635 0.635) (xy 0.635 0.635) (xy 0.635 -0.635)
			)
			(stroke
				(width 0)
				(type default)
			)
			(fill no)
			(layer "F.CrtYd")
		)
		(pad "1" smd rect
			(at 0 0)
			(size 1.27 1.27)
			(layers "F.Cu" "F.Mask" "F.Paste")
			(net "VDD_5.0V_EN")
		)
	)
	(footprint ""
		(layer "F.Cu")
		(at 81.407 37.973 180)
		(property "Reference" "R106"
			(at 0 0 180)
			(layer "F.SilkS")
			(hide yes)
			(effects
				(font
					(size 1.27 1.27)
				)
			)
		)
		(property "Value" "4.75K"
			(at -0.148158 1.3462 270)
			(unlocked yes)
			(layer "F.Fab")
			(hide yes)
			(effects
				(font
					(size 1.27 0.9652)
					(thickness 0.000001)
				)
				(justify left)
			)
		)
		(property "Device Type" "REST4024"
			(at -0.148158 1.3462 270)
			(unlocked yes)
			(layer "F.Fab")
			(hide yes)
			(effects
				(font
					(size 1.27 0.9652)
					(thickness 0.000001)
				)
				(justify left)
			)
		)
		(duplicate_pad_numbers_are_jumpers no)
		(fp_poly
			(pts
				(xy 0.635 1.0668) (xy 0.635 -1.0668) (xy -0.635 -1.0668) (xy -0.635 1.0668)
			)
			(stroke
				(width 0)
				(type default)
			)
			(fill no)
			(layer "F.CrtYd")
		)
		(fp_line
			(start 0.254 0.508)
			(end -0.254 0.508)
			(stroke
				(width 0.0254)
				(type default)
			)
			(layer "F.Fab")
		)
		(fp_line
			(start 0.254 -0.508)
			(end 0.254 0.508)
			(stroke
				(width 0.0254)
				(type default)
			)
			(layer "F.Fab")
		)
		(fp_line
			(start -0.254 0.508)
			(end -0.254 -0.508)
			(stroke
				(width 0.0254)
				(type default)
			)
			(layer "F.Fab")
		)
		(fp_line
			(start -0.254 -0.508)
			(end 0.254 -0.508)
			(stroke
				(width 0.0254)
				(type default)
			)
			(layer "F.Fab")
		)
		(pad "1" smd rect
			(at 0 -0.4191 180)
			(size 0.508 0.5334)
			(layers "F.Cu" "F.Mask" "F.Paste")
			(net "VDDQ_VTT_PGOOD")
		)
		(pad "2" smd rect
			(at 0 0.4191 180)
			(size 0.508 0.5334)
			(layers "F.Cu" "F.Mask" "F.Paste")
			(net "EXT_3.3V")
		)
		(zone
			(layer "F.Cu")
			(hatch none 0.5)
			(connect_pads
				(clearance 0)
			)
			(min_thickness 0.25)
			(keepout
				(tracks not_allowed)
				(vias allowed)
				(pads allowed)
				(copperpour not_allowed)
				(footprints allowed)
			)
			(placement
				(enabled no)
				(sheetname "")
			)
			(fill
				(thermal_gap 0.5)
				(thermal_bridge_width 0.5)
				(island_removal_mode 0)
			)
			(polygon
				(pts
					(xy 81.3816 37.9984) (xy 81.3816 37.9476) (xy 81.4324 37.9476) (xy 81.4324 37.9984)
				)
			)
		)
	)
	(footprint ""
		(layer "F.Cu")
		(at 7.2898 2.6416 180)
		(property "Reference" "DS1"
			(at 2.13233 1.143 90)
			(unlocked yes)
			(layer "F.SilkS")
			(effects
				(font
					(size 0.7874 0.5842)
					(thickness 0.127)
				)
				(justify left)
			)
		)
		(property "Value" "*"
			(at -0.2921 0.670154 180)
			(unlocked yes)
			(layer "F.Fab")
			(hide yes)
			(effects
				(font
					(size 0.7874 0.5842)
					(thickness 0.2032)
				)
				(justify left)
			)
		)
		(property "Device Type" "LEDS0007"
			(at -0.2921 0.670154 180)
			(unlocked yes)
			(layer "F.Fab")
			(hide yes)
			(effects
				(font
					(size 0.7874 0.5842)
					(thickness 0.2032)
				)
				(justify left)
			)
		)
		(duplicate_pad_numbers_are_jumpers no)
		(fp_line
			(start 2.413 0.762)
			(end 2.413 -0.762)
			(stroke
				(width 0.1524)
				(type default)
			)
			(layer "F.SilkS")
		)
		(fp_line
			(start 2.413 -0.762)
			(end 0.762 -0.762)
			(stroke
				(width 0.1524)
				(type default)
			)
			(layer "F.SilkS")
		)
		(fp_line
			(start 1.397 1.651)
			(end 1.397 0.762)
			(stroke
				(width 0.1524)
				(type default)
			)
			(layer "F.SilkS")
		)
		(fp_line
			(start 1.397 0.762)
			(end 2.413 0.762)
			(stroke
				(width 0.1524)
				(type default)
			)
			(layer "F.SilkS")
		)
		(fp_line
			(start 1.27 1.651)
			(end 1.397 1.651)
			(stroke
				(width 0.1524)
				(type default)
			)
			(layer "F.SilkS")
		)
		(fp_line
			(start 0.762 -0.762)
			(end 0.762 -1.143)
			(stroke
				(width 0.1524)
				(type default)
			)
			(layer "F.SilkS")
		)
		(fp_line
			(start 0.762 -1.143)
			(end -0.762 -1.143)
			(stroke
				(width 0.1524)
				(type default)
			)
			(layer "F.SilkS")
		)
		(fp_line
			(start -0.762 -0.762)
			(end -2.413 -0.762)
			(stroke
				(width 0.1524)
				(type default)
			)
			(layer "F.SilkS")
		)
		(fp_line
			(start -0.762 -0.762)
			(end -2.413 -0.762)
			(stroke
				(width 0.1524)
				(type default)
			)
			(layer "F.SilkS")
		)
		(fp_line
			(start -0.762 -0.889)
			(end -0.762 -0.762)
			(stroke
				(width 0.1524)
				(type default)
			)
			(layer "F.SilkS")
		)
		(fp_line
			(start -0.762 -1.143)
			(end -0.762 -0.762)
			(stroke
				(width 0.1524)
				(type default)
			)
			(layer "F.SilkS")
		)
		(fp_line
			(start -1.397 1.651)
			(end -1.27 1.651)
			(stroke
				(width 0.1524)
				(type default)
			)
			(layer "F.SilkS")
		)
		(fp_line
			(start -1.397 0.889)
			(end -1.397 0.762)
			(stroke
				(width 0.1524)
				(type default)
			)
			(layer "F.SilkS")
		)
		(fp_line
			(start -1.397 0.7747)
			(end -1.397 1.651)
			(stroke
				(width 0.1524)
				(type default)
			)
			(layer "F.SilkS")
		)
		(fp_line
			(start -1.397 0.762)
			(end -1.397 1.651)
			(stroke
				(width 0.1524)
				(type default)
			)
			(layer "F.SilkS")
		)
		(fp_line
			(start -2.286 0.889)
			(end -1.397 0.889)
			(stroke
				(width 0.1524)
				(type default)
			)
			(layer "F.SilkS")
		)
		(fp_line
			(start -2.413 0.762)
			(end -1.397 0.762)
			(stroke
				(width 0.1524)
				(type default)
			)
			(layer "F.SilkS")
		)
		(fp_line
			(start -2.413 -0.762)
			(end -2.413 0.762)
			(stroke
				(width 0.1524)
				(type default)
			)
			(layer "F.SilkS")
		)
		(fp_line
			(start -2.413 -0.762)
			(end -2.54 -0.889)
			(stroke
				(width 0.1524)
				(type default)
			)
			(layer "F.SilkS")
		)
		(fp_line
			(start -2.54 0.889)
			(end -1.397 0.889)
			(stroke
				(width 0.1524)
				(type default)
			)
			(layer "F.SilkS")
		)
		(fp_line
			(start -2.54 -0.889)
			(end -0.762 -0.889)
			(stroke
				(width 0.1524)
				(type default)
			)
			(layer "F.SilkS")
		)
		(fp_line
			(start -2.54 -0.889)
			(end -0.8255 -0.889)
			(stroke
				(width 0.1524)
				(type default)
			)
			(layer "F.SilkS")
		)
		(fp_line
			(start -2.54 -0.889)
			(end -2.54 0.889)
			(stroke
				(width 0.1524)
				(type default)
			)
			(layer "F.SilkS")
		)
		(fp_arc
			(start 1.27 1.651)
			(mid 0.898026 2.549026)
			(end 0 2.921)
			(stroke
				(width 0.1524)
				(type default)
			)
			(layer "F.SilkS")
		)
		(fp_arc
			(start 1.257986 1.825269)
			(mid 0.834139 2.608659)
			(end 0 2.921)
			(stroke
				(width 0.1524)
				(type default)
			)
			(layer "F.SilkS")
		)
		(fp_arc
			(start 0 2.921)
			(mid -0.898026 2.549026)
			(end -1.27 1.651)
			(stroke
				(width 0.1524)
				(type default)
			)
			(layer "F.SilkS")
		)
		(fp_poly
			(pts
				(arc
					(start 1.502689 1.905)
					(mid 1.396411 2.261432)
					(end 1.206957 2.581504)
				)
				(xy -0.889 2.581504) (xy -0.889 1.651) (xy -1.016 1.524) (xy -1.143 1.524) (xy -1.143 1.397) (xy -2.032 0.508)
				(xy -2.350872 0.508) (xy -2.350872 -1.016) (xy -1.016 -1.016) (xy -1.016 -1.397) (xy 1.016 -1.397)
				(xy 1.016 -1.016) (xy 2.667 -1.016) (xy 2.667 1.016) (xy 1.651 1.016) (xy 1.651 1.905)
			)
			(stroke
				(width 0)
				(type default)
			)
			(fill no)
			(layer "F.CrtYd")
		)
		(fp_line
			(start 1.4986 0.254)
			(end 1.4986 -0.254)
			(stroke
				(width 0.1524)
				(type default)
			)
			(layer "F.Fab")
		)
		(fp_line
			(start 1.4986 -0.254)
			(end -1.4986 -0.254)
			(stroke
				(width 0.1524)
				(type default)
			)
			(layer "F.Fab")
		)
		(fp_line
			(start 1.1049 1.3462)
			(end 1.1049 0.254)
			(stroke
				(width 0.1524)
				(type default)
			)
			(layer "F.Fab")
		)
		(fp_line
			(start 1.1049 0.254)
			(end -1.1049 0.254)
			(stroke
				(width 0.1524)
				(type default)
			)
			(layer "F.Fab")
		)
		(fp_line
			(start 0.9525 1.6002)
			(end 0.9525 1.3462)
			(stroke
				(width 0.1524)
				(type default)
			)
			(layer "F.Fab")
		)
		(fp_line
			(start 0.9525 1.3462)
			(end -0.9525 1.3462)
			(stroke
				(width 0.1524)
				(type default)
			)
			(layer "F.Fab")
		)
		(fp_line
			(start -0.0127 2.54)
			(end 0.0127 2.54)
			(stroke
				(width 0.1524)
				(type default)
			)
			(layer "F.Fab")
		)
		(fp_line
			(start -0.9525 1.3462)
			(end -0.9525 1.6002)
			(stroke
				(width 0.1524)
				(type default)
			)
			(layer "F.Fab")
		)
		(fp_line
			(start -1.1049 1.3462)
			(end 1.1049 1.3462)
			(stroke
				(width 0.1524)
				(type default)
			)
			(layer "F.Fab")
		)
		(fp_line
			(start -1.1049 0.254)
			(end -1.1049 1.3462)
			(stroke
				(width 0.1524)
				(type default)
			)
			(layer "F.Fab")
		)
		(fp_line
			(start -1.4986 0.254)
			(end 1.4986 0.254)
			(stroke
				(width 0.1524)
				(type default)
			)
			(layer "F.Fab")
		)
		(fp_line
			(start -1.4986 -0.254)
			(end -1.4986 0.254)
			(stroke
				(width 0.1524)
				(type default)
			)
			(layer "F.Fab")
		)
		(fp_arc
			(start 0.9525 1.6002)
			(mid 0.677239 2.264739)
			(end 0.0127 2.54)
			(stroke
				(width 0.1524)
				(type default)
			)
			(layer "F.Fab")
		)
		(fp_arc
			(start -0.0127 2.54)
			(mid -0.677239 2.264739)
			(end -0.9525 1.6002)
			(stroke
				(width 0.1524)
				(type default)
			)
			(layer "F.Fab")
		)
		(fp_text user "A"
			(at 3.175 -0.53467 0)
			(unlocked yes)
			(layer "F.SilkS")
			(effects
				(font
					(size 0.7874 0.5842)
					(thickness 0.127)
				)
				(justify left)
			)
		)
		(fp_text user "C"
			(at -1.651 1.49733 0)
			(unlocked yes)
			(layer "F.SilkS")
			(effects
				(font
					(size 0.7874 0.5842)
					(thickness 0.127)
				)
				(justify left)
			)
		)
		(fp_text user "A"
			(at 1.905 -0.91567 0)
			(unlocked yes)
			(layer "F.Fab")
			(effects
				(font
					(size 0.7874 0.5842)
					(thickness 0.127)
				)
				(justify left)
			)
		)
		(fp_text user "C"
			(at -1.143 -0.91567 0)
			(unlocked yes)
			(layer "F.Fab")
			(effects
				(font
					(size 0.7874 0.5842)
					(thickness 0.127)
				)
				(justify left)
			)
		)
		(pad "1" smd rect
			(at 1.4986 0 180)
			(size 1.1938 0.889)
			(layers "F.Cu" "F.Mask" "F.Paste")
			(net "EXT_3.3V")
		)
		(pad "2" smd rect
			(at 0 -0.4445 180)
			(size 0.9906 0.889)
			(layers "F.Cu" "F.Mask" "F.Paste")
			(net "9N2141")
		)
		(pad "3" smd rect
			(at -1.4986 0 180)
			(size 1.1938 0.889)
			(layers "F.Cu" "F.Mask" "F.Paste")
			(net "9N2152")
		)
	)
	(footprint ""
		(layer "F.Cu")
		(at 66.548 46.609)
		(property "Reference" "R113"
			(at 0 0 0)
			(layer "F.SilkS")
			(hide yes)
			(effects
				(font
					(size 1.27 1.27)
				)
			)
		)
		(property "Value" "732"
			(at -0.148158 1.3462 90)
			(unlocked yes)
			(layer "F.Fab")
			(hide yes)
			(effects
				(font
					(size 1.27 0.9652)
					(thickness 0.000001)
				)
				(justify left)
			)
		)
		(property "Device Type" "REST0289"
			(at -0.148158 1.3462 90)
			(unlocked yes)
			(layer "F.Fab")
			(hide yes)
			(effects
				(font
					(size 1.27 0.9652)
					(thickness 0.000001)
				)
				(justify left)
			)
		)
		(duplicate_pad_numbers_are_jumpers no)
		(fp_poly
			(pts
				(xy 0.635 1.0668) (xy 0.635 -1.0668) (xy -0.635 -1.0668) (xy -0.635 1.0668)
			)
			(stroke
				(width 0)
				(type default)
			)
			(fill no)
			(layer "F.CrtYd")
		)
		(fp_line
			(start -0.254 -0.508)
			(end 0.254 -0.508)
			(stroke
				(width 0.0254)
				(type default)
			)
			(layer "F.Fab")
		)
		(fp_line
			(start -0.254 0.508)
			(end -0.254 -0.508)
			(stroke
				(width 0.0254)
				(type default)
			)
			(layer "F.Fab")
		)
		(fp_line
			(start 0.254 -0.508)
			(end 0.254 0.508)
			(stroke
				(width 0.0254)
				(type default)
			)
			(layer "F.Fab")
		)
		(fp_line
			(start 0.254 0.508)
			(end -0.254 0.508)
			(stroke
				(width 0.0254)
				(type default)
			)
			(layer "F.Fab")
		)
		(pad "1" smd rect
			(at 0 -0.4191)
			(size 0.508 0.5334)
			(layers "F.Cu" "F.Mask" "F.Paste")
			(net "GND")
		)
		(pad "2" smd rect
			(at 0 0.4191)
			(size 0.508 0.5334)
			(layers "F.Cu" "F.Mask" "F.Paste")
			(net "11N1953")
		)
		(zone
			(layer "F.Cu")
			(hatch none 0.5)
			(connect_pads
				(clearance 0)
			)
			(min_thickness 0.25)
			(keepout
				(tracks not_allowed)
				(vias allowed)
				(pads allowed)
				(copperpour not_allowed)
				(footprints allowed)
			)
			(placement
				(enabled no)
				(sheetname "")
			)
			(fill
				(thermal_gap 0.5)
				(thermal_bridge_width 0.5)
				(island_removal_mode 0)
			)
			(polygon
				(pts
					(xy 66.5734 46.5836) (xy 66.5734 46.6344) (xy 66.5226 46.6344) (xy 66.5226 46.5836)
				)
			)
		)
	)
	(footprint ""
		(layer "F.Cu")
		(at 75.438 11.557)
		(property "Reference" "R362"
			(at -0.73533 1.778 90)
			(unlocked yes)
			(layer "F.SilkS")
			(effects
				(font
					(size 0.7874 0.5842)
					(thickness 0.127)
				)
				(justify left)
			)
		)
		(property "Value" "100"
			(at -0.148158 1.3462 90)
			(unlocked yes)
			(layer "F.Fab")
			(hide yes)
			(effects
				(font
					(size 1.27 0.9652)
					(thickness 0.000001)
				)
				(justify left)
			)
		)
		(property "Device Type" "REST4030"
			(at -0.148158 1.3462 90)
			(unlocked yes)
			(layer "F.Fab")
			(hide yes)
			(effects
				(font
					(size 1.27 0.9652)
					(thickness 0.000001)
				)
				(justify left)
			)
		)
		(duplicate_pad_numbers_are_jumpers no)
		(fp_poly
			(pts
				(xy 0.635 1.0668) (xy 0.635 -1.0668) (xy -0.635 -1.0668) (xy -0.635 1.0668)
			)
			(stroke
				(width 0)
				(type default)
			)
			(fill no)
			(layer "F.CrtYd")
		)
		(fp_line
			(start -0.254 -0.508)
			(end 0.254 -0.508)
			(stroke
				(width 0.0254)
				(type default)
			)
			(layer "F.Fab")
		)
		(fp_line
			(start -0.254 0.508)
			(end -0.254 -0.508)
			(stroke
				(width 0.0254)
				(type default)
			)
			(layer "F.Fab")
		)
		(fp_line
			(start 0.254 -0.508)
			(end 0.254 0.508)
			(stroke
				(width 0.0254)
				(type default)
			)
			(layer "F.Fab")
		)
		(fp_line
			(start 0.254 0.508)
			(end -0.254 0.508)
			(stroke
				(width 0.0254)
				(type default)
			)
			(layer "F.Fab")
		)
		(pad "1" smd rect
			(at 0 -0.4191)
			(size 0.508 0.5334)
			(layers "F.Cu" "F.Mask" "F.Paste")
			(net "DDR0_32A_VREF1B")
		)
		(pad "2" smd rect
			(at 0 0.4191)
			(size 0.508 0.5334)
			(layers "F.Cu" "F.Mask" "F.Paste")
			(net "DDR_VDDQ")
		)
		(zone
			(layer "F.Cu")
			(hatch none 0.5)
			(connect_pads
				(clearance 0)
			)
			(min_thickness 0.25)
			(keepout
				(tracks not_allowed)
				(vias allowed)
				(pads allowed)
				(copperpour not_allowed)
				(footprints allowed)
			)
			(placement
				(enabled no)
				(sheetname "")
			)
			(fill
				(thermal_gap 0.5)
				(thermal_bridge_width 0.5)
				(island_removal_mode 0)
			)
			(polygon
				(pts
					(xy 75.4634 11.5316) (xy 75.4634 11.5824) (xy 75.4126 11.5824) (xy 75.4126 11.5316)
				)
			)
		)
	)
)
